(kicad_pcb
	(version 20241229)
	(generator "pcbnew")
	(generator_version "9.0")
	(general
		(thickness 1.61)
		(legacy_teardrops no)
	)
	(paper "A3")
	(title_block
		(title "RDIMM DDR5 Tester")
		(date "2026-05-21")
		(rev "2.2.0")
		(company "Antmicro")
		(comment 9 "footprint 119 of 796 (U34), pads 395-465 of 676")
	)
	(layers
		(0 "F.Cu" signal)
		(4 "In1.Cu" power)
		(6 "In2.Cu" mixed)
		(8 "In3.Cu" power)
		(10 "In4.Cu" mixed)
		(12 "In5.Cu" power)
		(14 "In6.Cu" mixed)
		(16 "In7.Cu" power)
		(18 "In8.Cu" power)
		(20 "In9.Cu" mixed)
		(22 "In10.Cu" power)
		(2 "B.Cu" signal)
		(9 "F.Adhes" user "F.Adhesive")
		(11 "B.Adhes" user "B.Adhesive")
		(13 "F.Paste" user)
		(15 "B.Paste" user)
		(5 "F.SilkS" user "F.Silkscreen")
		(7 "B.SilkS" user "B.Silkscreen")
		(1 "F.Mask" user)
		(3 "B.Mask" user)
		(17 "Dwgs.User" user "User.Drawings")
		(19 "Cmts.User" user "User.Comments")
		(21 "Eco1.User" user "User.Eco1")
		(23 "Eco2.User" user "User.Eco2")
		(25 "Edge.Cuts" user)
		(27 "Margin" user)
		(31 "F.CrtYd" user "F.Courtyard")
		(29 "B.CrtYd" user "B.Courtyard")
		(35 "F.Fab" user)
		(33 "B.Fab" user)
	)
	(footprint "antmicro-footprints:BGA-676_27x27mm_Layout26x26_P1x1mm_FFVB676"
		(layer "F.Cu")
		(at 188.5 152.5 90)
		(property "Reference" "U34"
			(at -14.72 12.46 180)
			(layer "F.SilkS")
			(effects
				(font
					(size 0.7 0.7)
					(thickness 0.15)
				)
				(justify left bottom)
			)
		)
		(property "Value" "XCAU25P-2FFVB676I"
			(at 0 15.5 90)
			(layer "F.Fab")
			(effects
				(font
					(size 0.7 0.7)
					(thickness 0.15)
				)
				(justify left bottom)
			)
		)
		(property "Datasheet" "https://docs.xilinx.com/viewer/book-attachment/2PXOpPtpaABIt0fkzeBLnw/hvbsEUaOT0OxFhln7VEVyA"
			(at 0 0 90)
			(layer "F.Fab")
			(hide yes)
			(effects
				(font
					(size 1.27 1.27)
					(thickness 0.15)
				)
			)
		)
		(property "MPN" "XCAU25P-2FFVB676I"
			(at 0 0 90)
			(unlocked yes)
			(layer "F.Fab")
			(hide yes)
			(effects
				(font
					(size 1 1)
					(thickness 0.15)
				)
			)
		)
		(property "Manufacturer" "AMD-Xilinx"
			(at 0 0 90)
			(unlocked yes)
			(layer "F.Fab")
			(hide yes)
			(effects
				(font
					(size 1 1)
					(thickness 0.15)
				)
			)
		)
		(property "Author" "Antmicro"
			(at 0 0 90)
			(unlocked yes)
			(layer "F.Fab")
			(hide yes)
			(effects
				(font
					(size 1 1)
					(thickness 0.15)
				)
			)
		)
		(property "License" "Apache-2.0"
			(at 0 0 90)
			(unlocked yes)
			(layer "F.Fab")
			(hide yes)
			(effects
				(font
					(size 1 1)
					(thickness 0.15)
				)
			)
		)
		(sheetname "/FPGA Config/")
		(sheetfile "fpga-config.kicad_sch")
		(attr smd)
		(pad "K5" smd circle
			(at -8.5 -3.5 90)
			(size 0.5 0.5)
			(layers "F.Cu" "F.Mask" "F.Paste")
			(net 172 "+1V2_MGTAVTT")
			(pinfunction "MGTAVTT_R")
			(pintype "passive")
			(solder_mask_margin 0.075)
		)
		(pad "K6" smd circle
			(at -7.5 -3.5 90)
			(size 0.5 0.5)
			(layers "F.Cu" "F.Mask" "F.Paste")
			(net 551 "unconnected-(U34L-NC-PadK6)")
			(pinfunction "NC")
			(pintype "no_connect")
			(solder_mask_margin 0.075)
		)
		(pad "K7" smd circle
			(at -6.5 -3.5 90)
			(size 0.5 0.5)
			(layers "F.Cu" "F.Mask" "F.Paste")
			(net 552 "unconnected-(U34L-NC-PadK7)")
			(pinfunction "NC")
			(pintype "no_connect")
			(solder_mask_margin 0.075)
		)
		(pad "K8" smd circle
			(at -5.5 -3.5 90)
			(size 0.5 0.5)
			(layers "F.Cu" "F.Mask" "F.Paste")
			(net 1 "GND")
			(pinfunction "GND")
			(pintype "passive")
			(solder_mask_margin 0.075)
		)
		(pad "K9" smd circle
			(at -4.5 -3.5 90)
			(size 0.5 0.5)
			(layers "F.Cu" "F.Mask" "F.Paste")
			(net 700 "/FPGA banks HD/USR_LED4")
			(pinfunction "IO_L1N_AD11N_86")
			(pintype "bidirectional")
			(die_length 16.677)
			(solder_mask_margin 0.075)
		)
		(pad "K10" smd circle
			(at -3.5 -3.5 90)
			(size 0.5 0.5)
			(layers "F.Cu" "F.Mask" "F.Paste")
			(net 701 "/FPGA banks HD/USR_LED5")
			(pinfunction "IO_L1P_AD11P_86")
			(pintype "bidirectional")
			(die_length 15.605)
			(solder_mask_margin 0.075)
		)
		(pad "K11" smd circle
			(at -2.5 -3.5 90)
			(size 0.5 0.5)
			(layers "F.Cu" "F.Mask" "F.Paste")
			(net 553 "+0V85")
			(pinfunction "VCCINT")
			(pintype "power_in")
			(solder_mask_margin 0.075)
		)
		(pad "K12" smd circle
			(at -1.5 -3.5 90)
			(size 0.5 0.5)
			(layers "F.Cu" "F.Mask" "F.Paste")
			(net 1 "GND")
			(pinfunction "GND")
			(pintype "passive")
			(solder_mask_margin 0.075)
		)
		(pad "K13" smd circle
			(at -0.5 -3.5 90)
			(size 0.5 0.5)
			(layers "F.Cu" "F.Mask" "F.Paste")
			(net 553 "+0V85")
			(pinfunction "VCCINT")
			(pintype "passive")
			(solder_mask_margin 0.075)
		)
		(pad "K14" smd circle
			(at 0.5 -3.5 90)
			(size 0.5 0.5)
			(layers "F.Cu" "F.Mask" "F.Paste")
			(net 1 "GND")
			(pinfunction "GND")
			(pintype "passive")
			(solder_mask_margin 0.075)
		)
		(pad "K15" smd circle
			(at 1.5 -3.5 90)
			(size 0.5 0.5)
			(layers "F.Cu" "F.Mask" "F.Paste")
			(net 553 "+0V85")
			(pinfunction "VCCINT")
			(pintype "passive")
			(solder_mask_margin 0.075)
		)
		(pad "K16" smd circle
			(at 2.5 -3.5 90)
			(size 0.5 0.5)
			(layers "F.Cu" "F.Mask" "F.Paste")
			(net 1 "GND")
			(pinfunction "GND")
			(pintype "passive")
			(solder_mask_margin 0.075)
		)
		(pad "K17" smd circle
			(at 3.5 -3.5 90)
			(size 0.5 0.5)
			(layers "F.Cu" "F.Mask" "F.Paste")
			(net 553 "+0V85")
			(pinfunction "VCCINT")
			(pintype "passive")
			(solder_mask_margin 0.075)
		)
		(pad "K18" smd circle
			(at 4.5 -3.5 90)
			(size 0.5 0.5)
			(layers "F.Cu" "F.Mask" "F.Paste")
			(net 133 "/DDR5 RDIMM/B.DQS0_N")
			(pinfunction "IO_L1N_T0L_N1_DBC_66")
			(pintype "bidirectional")
			(die_length 19.351)
			(solder_mask_margin 0.075)
		)
		(pad "K19" smd circle
			(at 5.5 -3.5 90)
			(size 0.5 0.5)
			(layers "F.Cu" "F.Mask" "F.Paste")
			(net 1 "GND")
			(pinfunction "GND")
			(pintype "passive")
			(solder_mask_margin 0.075)
		)
		(pad "K20" smd circle
			(at 6.5 -3.5 90)
			(size 0.5 0.5)
			(layers "F.Cu" "F.Mask" "F.Paste")
			(net 111 "/DDR5 RDIMM/B.DQ5")
			(pinfunction "IO_L6N_T0U_N11_AD6N_66")
			(pintype "bidirectional")
			(die_length 15.537)
			(solder_mask_margin 0.075)
		)
		(pad "K21" smd circle
			(at 7.5 -3.5 90)
			(size 0.5 0.5)
			(layers "F.Cu" "F.Mask" "F.Paste")
			(net 110 "/DDR5 RDIMM/B.DQ4")
			(pinfunction "IO_L5P_T0U_N8_AD14P_66")
			(pintype "bidirectional")
			(die_length 15.555)
			(solder_mask_margin 0.075)
		)
		(pad "K22" smd circle
			(at 8.5 -3.5 90)
			(size 0.5 0.5)
			(layers "F.Cu" "F.Mask" "F.Paste")
			(net 359 "/DDR5 RDIMM/B.DQ15")
			(pinfunction "IO_L11P_T1U_N8_GC_66")
			(pintype "bidirectional")
			(die_length 11.234)
			(solder_mask_margin 0.075)
		)
		(pad "K23" smd circle
			(at 9.5 -3.5 90)
			(size 0.5 0.5)
			(layers "F.Cu" "F.Mask" "F.Paste")
			(net 117 "/DDR5 RDIMM/B.DQ13")
			(pinfunction "IO_L11N_T1U_N9_GC_66")
			(pintype "bidirectional")
			(die_length 11.109)
			(solder_mask_margin 0.075)
		)
		(pad "K24" smd circle
			(at 10.5 -3.5 90)
			(size 0.5 0.5)
			(layers "F.Cu" "F.Mask" "F.Paste")
			(net 1 "GND")
			(pinfunction "GND")
			(pintype "passive")
			(solder_mask_margin 0.075)
		)
		(pad "K25" smd circle
			(at 11.5 -3.5 90)
			(size 0.5 0.5)
			(layers "F.Cu" "F.Mask" "F.Paste")
			(net 229 "/DDR5 RDIMM/B.DQ11")
			(pinfunction "IO_L9P_T1L_N4_AD12P_66")
			(pintype "bidirectional")
			(die_length 13.374)
			(solder_mask_margin 0.075)
		)
		(pad "K26" smd circle
			(at 12.5 -3.5 90)
			(size 0.5 0.5)
			(layers "F.Cu" "F.Mask" "F.Paste")
			(net 219 "/DDR5 RDIMM/B.DQ10")
			(pinfunction "IO_L9N_T1L_N5_AD12N_66")
			(pintype "bidirectional")
			(die_length 13.552)
			(solder_mask_margin 0.075)
		)
		(pad "L1" smd circle
			(at -12.5 -2.5 90)
			(size 0.5 0.5)
			(layers "F.Cu" "F.Mask" "F.Paste")
			(net 1 "GND")
			(pinfunction "GND")
			(pintype "passive")
			(solder_mask_margin 0.075)
		)
		(pad "L2" smd circle
			(at -11.5 -2.5 90)
			(size 0.5 0.5)
			(layers "F.Cu" "F.Mask" "F.Paste")
			(net 1 "GND")
			(pinfunction "GND")
			(pintype "passive")
			(solder_mask_margin 0.075)
		)
		(pad "L3" smd circle
			(at -10.5 -2.5 90)
			(size 0.5 0.5)
			(layers "F.Cu" "F.Mask" "F.Paste")
			(net 1 "GND")
			(pinfunction "GND")
			(pintype "passive")
			(solder_mask_margin 0.075)
		)
		(pad "L4" smd circle
			(at -9.5 -2.5 90)
			(size 0.5 0.5)
			(layers "F.Cu" "F.Mask" "F.Paste")
			(net 629 "/FPGA MGT Interface/HDMI_FPGA.TX1_N")
			(pinfunction "MGTYTXN1_226")
			(pintype "output")
			(die_length 7.883)
			(solder_mask_margin 0.075)
		)
		(pad "L5" smd circle
			(at -8.5 -2.5 90)
			(size 0.5 0.5)
			(layers "F.Cu" "F.Mask" "F.Paste")
			(net 630 "/FPGA MGT Interface/HDMI_FPGA.TX1_P")
			(pinfunction "MGTYTXP1_226")
			(pintype "output")
			(die_length 7.909)
			(solder_mask_margin 0.075)
		)
		(pad "L6" smd circle
			(at -7.5 -2.5 90)
			(size 0.5 0.5)
			(layers "F.Cu" "F.Mask" "F.Paste")
			(net 1 "GND")
			(pinfunction "GND")
			(pintype "passive")
			(solder_mask_margin 0.075)
		)
		(pad "L7" smd circle
			(at -6.5 -2.5 90)
			(size 0.5 0.5)
			(layers "F.Cu" "F.Mask" "F.Paste")
			(net 820 "+0V9_MGTAVCC")
			(pinfunction "MGTAVCC_R")
			(pintype "passive")
			(solder_mask_margin 0.075)
		)
		(pad "L8" smd circle
			(at -5.5 -2.5 90)
			(size 0.5 0.5)
			(layers "F.Cu" "F.Mask" "F.Paste")
			(net 1 "GND")
			(pinfunction "GND")
			(pintype "passive")
			(solder_mask_margin 0.075)
		)
		(pad "L9" smd circle
			(at -4.5 -2.5 90)
			(size 0.5 0.5)
			(layers "F.Cu" "F.Mask" "F.Paste")
			(net 553 "+0V85")
			(pinfunction "VCCINT_IO")
			(pintype "power_in")
			(solder_mask_margin 0.075)
		)
		(pad "L10" smd circle
			(at -3.5 -2.5 90)
			(size 0.5 0.5)
			(layers "F.Cu" "F.Mask" "F.Paste")
			(net 553 "+0V85")
			(pinfunction "VCCINT")
			(pintype "passive")
			(solder_mask_margin 0.075)
		)
		(pad "L11" smd circle
			(at -2.5 -2.5 90)
			(size 0.5 0.5)
			(layers "F.Cu" "F.Mask" "F.Paste")
			(net 1 "GND")
			(pinfunction "GND")
			(pintype "passive")
			(solder_mask_margin 0.075)
		)
		(pad "L12" smd circle
			(at -1.5 -2.5 90)
			(size 0.5 0.5)
			(layers "F.Cu" "F.Mask" "F.Paste")
			(net 553 "+0V85")
			(pinfunction "VCCINT")
			(pintype "passive")
			(solder_mask_margin 0.075)
		)
		(pad "L13" smd circle
			(at -0.5 -2.5 90)
			(size 0.5 0.5)
			(layers "F.Cu" "F.Mask" "F.Paste")
			(net 1 "GND")
			(pinfunction "GND")
			(pintype "passive")
			(solder_mask_margin 0.075)
		)
		(pad "L14" smd circle
			(at 0.5 -2.5 90)
			(size 0.5 0.5)
			(layers "F.Cu" "F.Mask" "F.Paste")
			(net 553 "+0V85")
			(pinfunction "VCCINT")
			(pintype "passive")
			(solder_mask_margin 0.075)
		)
		(pad "L15" smd circle
			(at 1.5 -2.5 90)
			(size 0.5 0.5)
			(layers "F.Cu" "F.Mask" "F.Paste")
			(net 1 "GND")
			(pinfunction "GND")
			(pintype "passive")
			(solder_mask_margin 0.075)
		)
		(pad "L16" smd circle
			(at 2.5 -2.5 90)
			(size 0.5 0.5)
			(layers "F.Cu" "F.Mask" "F.Paste")
			(net 553 "+0V85")
			(pinfunction "VCCINT")
			(pintype "passive")
			(solder_mask_margin 0.075)
		)
		(pad "L17" smd circle
			(at 3.5 -2.5 90)
			(size 0.5 0.5)
			(layers "F.Cu" "F.Mask" "F.Paste")
			(net 1 "GND")
			(pinfunction "GND")
			(pintype "passive")
			(solder_mask_margin 0.075)
		)
		(pad "L18" smd circle
			(at 4.5 -2.5 90)
			(size 0.5 0.5)
			(layers "F.Cu" "F.Mask" "F.Paste")
			(net 132 "/DDR5 RDIMM/B.DQS0_P")
			(pinfunction "IO_L1P_T0L_N0_DBC_66")
			(pintype "bidirectional")
			(die_length 19.491)
			(solder_mask_margin 0.075)
		)
		(pad "L19" smd circle
			(at 5.5 -2.5 90)
			(size 0.5 0.5)
			(layers "F.Cu" "F.Mask" "F.Paste")
			(net 457 "/DDR5 RDIMM/B.DQS5_N")
			(pinfunction "IO_L4N_T0U_N7_DBC_AD7N_66")
			(pintype "bidirectional")
			(die_length 15.594)
			(solder_mask_margin 0.075)
		)
		(pad "L20" smd circle
			(at 6.5 -2.5 90)
			(size 0.5 0.5)
			(layers "F.Cu" "F.Mask" "F.Paste")
			(net 217 "/DDR5 RDIMM/B.DQ6")
			(pinfunction "IO_L6P_T0U_N10_AD6P_66")
			(pintype "bidirectional")
			(die_length 15.624)
			(solder_mask_margin 0.075)
		)
		(pad "L21" smd circle
			(at 7.5 -2.5 90)
			(size 0.5 0.5)
			(layers "F.Cu" "F.Mask" "F.Paste")
			(net 1 "GND")
			(pinfunction "GND")
			(pintype "passive")
			(solder_mask_margin 0.075)
		)
		(pad "L22" smd circle
			(at 8.5 -2.5 90)
			(size 0.5 0.5)
			(layers "F.Cu" "F.Mask" "F.Paste")
			(net 141 "/DDR5 RDIMM/B.DQS1_P")
			(pinfunction "IO_L7P_T1L_N0_QBC_AD13P_66")
			(pintype "bidirectional")
			(die_length 9.844)
			(solder_mask_margin 0.075)
		)
		(pad "L23" smd circle
			(at 9.5 -2.5 90)
			(size 0.5 0.5)
			(layers "F.Cu" "F.Mask" "F.Paste")
			(net 142 "/DDR5 RDIMM/B.DQS1_N")
			(pinfunction "IO_L7N_T1L_N1_QBC_AD13N_66")
			(pintype "bidirectional")
			(die_length 9.768)
			(solder_mask_margin 0.075)
		)
		(pad "L24" smd circle
			(at 10.5 -2.5 90)
			(size 0.5 0.5)
			(layers "F.Cu" "F.Mask" "F.Paste")
			(net 593 "/DDR5 RDIMM/B.DQS6_P")
			(pinfunction "IO_L10P_T1U_N6_QBC_AD4P_66")
			(pintype "bidirectional")
			(die_length 11.633)
			(solder_mask_margin 0.075)
		)
		(pad "L25" smd circle
			(at 11.5 -2.5 90)
			(size 0.5 0.5)
			(layers "F.Cu" "F.Mask" "F.Paste")
			(net 592 "/DDR5 RDIMM/B.DQS6_N")
			(pinfunction "IO_L10N_T1U_N7_QBC_AD4N_66")
			(pintype "bidirectional")
			(die_length 11.533)
			(solder_mask_margin 0.075)
		)
		(pad "L26" smd circle
			(at 12.5 -2.5 90)
			(size 0.5 0.5)
			(layers "F.Cu" "F.Mask" "F.Paste")
			(net 1 "GND")
			(pinfunction "GND")
			(pintype "passive")
			(solder_mask_margin 0.075)
		)
		(pad "M1" smd circle
			(at -12.5 -1.5 90)
			(size 0.5 0.5)
			(layers "F.Cu" "F.Mask" "F.Paste")
			(net 652 "/FPGA MGT Interface/HDMI_FPGA.RX0_N")
			(pinfunction "MGTYRXN0_226")
			(pintype "input")
			(die_length 9.858)
			(solder_mask_margin 0.075)
		)
		(pad "M2" smd circle
			(at -11.5 -1.5 90)
			(size 0.5 0.5)
			(layers "F.Cu" "F.Mask" "F.Paste")
			(net 653 "/FPGA MGT Interface/HDMI_FPGA.RX0_P")
			(pinfunction "MGTYRXP0_226")
			(pintype "input")
			(die_length 9.85)
			(solder_mask_margin 0.075)
		)
		(pad "M3" smd circle
			(at -10.5 -1.5 90)
			(size 0.5 0.5)
			(layers "F.Cu" "F.Mask" "F.Paste")
			(net 1 "GND")
			(pinfunction "GND")
			(pintype "passive")
			(solder_mask_margin 0.075)
		)
		(pad "M4" smd circle
			(at -9.5 -1.5 90)
			(size 0.5 0.5)
			(layers "F.Cu" "F.Mask" "F.Paste")
			(net 1 "GND")
			(pinfunction "GND")
			(pintype "passive")
			(solder_mask_margin 0.075)
		)
		(pad "M5" smd circle
			(at -8.5 -1.5 90)
			(size 0.5 0.5)
			(layers "F.Cu" "F.Mask" "F.Paste")
			(net 172 "+1V2_MGTAVTT")
			(pinfunction "MGTAVTT_R")
			(pintype "passive")
			(solder_mask_margin 0.075)
		)
		(pad "M6" smd circle
			(at -7.5 -1.5 90)
			(size 0.5 0.5)
			(layers "F.Cu" "F.Mask" "F.Paste")
			(net 291 "/FPGA MGT Interface/HDMI_IN_CLK_C_N")
			(pinfunction "MGTREFCLK1N_226")
			(pintype "input")
			(die_length 5.554)
			(solder_mask_margin 0.075)
		)
		(pad "M7" smd circle
			(at -6.5 -1.5 90)
			(size 0.5 0.5)
			(layers "F.Cu" "F.Mask" "F.Paste")
			(net 268 "/FPGA MGT Interface/HDMI_IN_CLK_C_P")
			(pinfunction "MGTREFCLK1P_226")
			(pintype "input")
			(die_length 5.516)
			(solder_mask_margin 0.075)
		)
		(pad "M8" smd circle
			(at -5.5 -1.5 90)
			(size 0.5 0.5)
			(layers "F.Cu" "F.Mask" "F.Paste")
			(net 1 "GND")
			(pinfunction "GND")
			(pintype "passive")
			(solder_mask_margin 0.075)
		)
		(pad "M9" smd circle
			(at -4.5 -1.5 90)
			(size 0.5 0.5)
			(layers "F.Cu" "F.Mask" "F.Paste")
			(net 553 "+0V85")
			(pinfunction "VCCINT_IO")
			(pintype "passive")
			(solder_mask_margin 0.075)
		)
		(pad "M10" smd circle
			(at -3.5 -1.5 90)
			(size 0.5 0.5)
			(layers "F.Cu" "F.Mask" "F.Paste")
			(net 1 "GND")
			(pinfunction "GND")
			(pintype "passive")
			(solder_mask_margin 0.075)
		)
		(pad "M11" smd circle
			(at -2.5 -1.5 90)
			(size 0.5 0.5)
			(layers "F.Cu" "F.Mask" "F.Paste")
			(net 553 "+0V85")
			(pinfunction "VCCINT")
			(pintype "passive")
			(solder_mask_margin 0.075)
		)
		(pad "M12" smd circle
			(at -1.5 -1.5 90)
			(size 0.5 0.5)
			(layers "F.Cu" "F.Mask" "F.Paste")
			(net 1 "GND")
			(pinfunction "GND")
			(pintype "passive")
			(solder_mask_margin 0.075)
		)
		(pad "M13" smd circle
			(at -0.5 -1.5 90)
			(size 0.5 0.5)
			(layers "F.Cu" "F.Mask" "F.Paste")
			(net 553 "+0V85")
			(pinfunction "VCCINT")
			(pintype "passive")
			(solder_mask_margin 0.075)
		)
		(pad "M14" smd circle
			(at 0.5 -1.5 90)
			(size 0.5 0.5)
			(layers "F.Cu" "F.Mask" "F.Paste")
			(net 1 "GND")
			(pinfunction "GND")
			(pintype "passive")
			(solder_mask_margin 0.075)
		)
		(pad "M15" smd circle
			(at 1.5 -1.5 90)
			(size 0.5 0.5)
			(layers "F.Cu" "F.Mask" "F.Paste")
			(net 553 "+0V85")
			(pinfunction "VCCINT")
			(pintype "passive")
			(solder_mask_margin 0.075)
		)
		(pad "M16" smd circle
			(at 2.5 -1.5 90)
			(size 0.5 0.5)
			(layers "F.Cu" "F.Mask" "F.Paste")
			(net 1 "GND")
			(pinfunction "GND")
			(pintype "passive")
			(solder_mask_margin 0.075)
		)
		(pad "M17" smd circle
			(at 3.5 -1.5 90)
			(size 0.5 0.5)
			(layers "F.Cu" "F.Mask" "F.Paste")
			(net 553 "+0V85")
			(pinfunction "VCCINT")
			(pintype "passive")
			(solder_mask_margin 0.075)
		)
		(pad "M18" smd circle
			(at 4.5 -1.5 90)
			(size 0.5 0.5)
			(layers "F.Cu" "F.Mask" "F.Paste")
			(net 797 "+1V8")
			(pinfunction "VCCAUX")
			(pintype "power_in")
			(solder_mask_margin 0.075)
		)
		(pad "M19" smd circle
			(at 5.5 -1.5 90)
			(size 0.5 0.5)
			(layers "F.Cu" "F.Mask" "F.Paste")
			(net 474 "/DDR5 RDIMM/B.DQS5_P")
			(pinfunction "IO_L4P_T0U_N6_DBC_AD7P_66")
			(pintype "bidirectional")
			(die_length 15.54)
			(solder_mask_margin 0.075)
		)
		(pad "M20" smd circle
			(at 6.5 -1.5 90)
			(size 0.5 0.5)
			(layers "F.Cu" "F.Mask" "F.Paste")
			(net 107 "/DDR5 RDIMM/B.DQ1")
			(pinfunction "IO_L2P_T0L_N2_66")
			(pintype "bidirectional")
			(die_length 15.56)
			(solder_mask_margin 0.075)
		)
		(pad "M21" smd circle
			(at 7.5 -1.5 90)
			(size 0.5 0.5)
			(layers "F.Cu" "F.Mask" "F.Paste")
			(net 106 "/DDR5 RDIMM/B.DQ0")
			(pinfunction "IO_L2N_T0L_N3_66")
			(pintype "bidirectional")
			(die_length 16.141)
			(solder_mask_margin 0.075)
		)
		(pad "M22" smd circle
			(at 8.5 -1.5 90)
			(size 0.5 0.5)
			(layers "F.Cu" "F.Mask" "F.Paste")
			(net 600 "/FPGA banks HP/VRP_66")
			(pinfunction "IO_T0U_N12_VRP_66")
			(pintype "bidirectional")
			(die_length 15.559)
			(solder_mask_margin 0.075)
		)
		(pad "M23" smd circle
			(at 9.5 -1.5 90)
			(size 0.5 0.5)
			(layers "F.Cu" "F.Mask" "F.Paste")
			(net 1 "GND")
			(pinfunction "GND")
			(pintype "passive")
			(solder_mask_margin 0.075)
		)
	)
)
